(kicad_pcb
	(version 20241229)
	(generator "pcbnew")
	(generator_version "9.0")
	(general
		(thickness 1.6642)
		(legacy_teardrops no)
	)
	(paper "A3")
	(title_block
		(title "PolarFire SoM")
		(date "2025-07-22")
		(rev "1.1.4")
		(company "Antmicro Ltd")
		(comment 1 "www.antmicro.com")
		(comment 9 "footprints 75-79 of 470")
	)
	(layers
		(0 "F.Cu" mixed)
		(4 "In1.Cu" power)
		(6 "In2.Cu" signal)
		(8 "In3.Cu" power)
		(10 "In4.Cu" signal)
		(12 "In5.Cu" power)
		(14 "In6.Cu" power)
		(16 "In7.Cu" signal)
		(18 "In8.Cu" power)
		(20 "In9.Cu" signal)
		(22 "In10.Cu" power)
		(24 "In11.Cu" signal)
		(26 "In12.Cu" signal)
		(2 "B.Cu" mixed)
		(9 "F.Adhes" user "F.Adhesive")
		(11 "B.Adhes" user "B.Adhesive")
		(13 "F.Paste" user)
		(15 "B.Paste" user)
		(5 "F.SilkS" user "F.Silkscreen")
		(7 "B.SilkS" user "B.Silkscreen")
		(1 "F.Mask" user)
		(3 "B.Mask" user)
		(17 "Dwgs.User" user "User.Drawings")
		(19 "Cmts.User" user "User.Comments")
		(21 "Eco1.User" user "User.Eco1")
		(23 "Eco2.User" user "User.Eco2")
		(25 "Edge.Cuts" user)
		(27 "Margin" user)
		(31 "F.CrtYd" user "F.Courtyard")
		(29 "B.CrtYd" user "B.Courtyard")
		(35 "F.Fab" user)
		(33 "B.Fab" user)
	)
	(footprint "antmicro-footprints:TP_SMD_0.75mm"
		(layer "F.Cu")
		(at 228.47 145.275)
		(property "Reference" "TP30"
			(at 9.74 1.515 0)
			(layer "F.SilkS")
			(hide yes)
			(effects
				(font
					(size 0.7 0.7)
					(thickness 0.15)
				)
				(justify left bottom)
			)
		)
		(property "Value" "TP_0.75mm_SMD"
			(at 0 1.2 0)
			(layer "F.Fab")
			(hide yes)
			(effects
				(font
					(size 0.7 0.7)
					(thickness 0.15)
				)
				(justify left bottom)
			)
		)
		(property "Description" "SMT test point"
			(at 0 0 0)
			(layer "F.Fab")
			(hide yes)
			(effects
				(font
					(size 1.27 1.27)
					(thickness 0.15)
				)
			)
		)
		(property "Author" "Antmicro"
			(at 0 0 0)
			(layer "F.Fab")
			(hide yes)
			(effects
				(font
					(size 1 1)
					(thickness 0.15)
				)
			)
		)
		(property "License" "Apache-2.0"
			(at 0 0 0)
			(layer "F.Fab")
			(hide yes)
			(effects
				(font
					(size 1 1)
					(thickness 0.15)
				)
			)
		)
		(property "MPN" ""
			(at 0 0 0)
			(layer "F.Fab")
			(hide yes)
			(effects
				(font
					(size 1 1)
					(thickness 0.15)
				)
			)
		)
		(property "Manufacturer" ""
			(at 0 0 0)
			(layer "F.Fab")
			(hide yes)
			(effects
				(font
					(size 1 1)
					(thickness 0.15)
				)
			)
		)
		(property "Public" "False"
			(at 0 0 0)
			(layer "F.Fab")
			(hide yes)
			(effects
				(font
					(size 1 1)
					(thickness 0.15)
				)
			)
		)
		(sheetname "/WiFi_Bluetooth/")
		(sheetfile "wifi_bt.kicad_sch")
		(attr exclude_from_pos_files exclude_from_bom)
		(fp_circle
			(center 0 0)
			(end 0.475 0)
			(stroke
				(width 0.05)
				(type default)
			)
			(fill no)
			(layer "F.CrtYd")
		)
		(fp_text user "License: Apache-2.0"
			(at -0.4 5.101 0)
			(layer "F.Fab")
			(effects
				(font
					(size 0.7 0.7)
					(thickness 0.15)
				)
				(justify left bottom)
			)
		)
		(fp_text user "${REFERENCE}"
			(at -0.4 2.7 0)
			(layer "F.Fab")
			(effects
				(font
					(size 0.7 0.7)
					(thickness 0.15)
				)
				(justify left bottom)
			)
		)
		(fp_text user "Author: Antmicro"
			(at -0.4 3.901 0)
			(layer "F.Fab")
			(effects
				(font
					(size 0.7 0.7)
					(thickness 0.15)
				)
				(justify left bottom)
			)
		)
		(pad "1" smd circle
			(at 0 0)
			(size 0.75 0.75)
			(layers "F.Cu" "F.Mask")
			(net 527 "Net-(U26A-BT_GPIO_2)")
			(pinfunction "1")
			(pintype "passive")
		)
	)
	(footprint "antmicro-footprints:TP_SMD_0.75mm"
		(layer "F.Cu")
		(at 227.2 145.91)
		(property "Reference" "TP29"
			(at 10.39 1.84 0)
			(layer "F.SilkS")
			(hide yes)
			(effects
				(font
					(size 0.7 0.7)
					(thickness 0.15)
				)
				(justify left bottom)
			)
		)
		(property "Value" "TP_0.75mm_SMD"
			(at 0 1.2 0)
			(layer "F.Fab")
			(hide yes)
			(effects
				(font
					(size 0.7 0.7)
					(thickness 0.15)
				)
				(justify left bottom)
			)
		)
		(property "Description" "SMT test point"
			(at 0 0 0)
			(layer "F.Fab")
			(hide yes)
			(effects
				(font
					(size 1.27 1.27)
					(thickness 0.15)
				)
			)
		)
		(property "Author" "Antmicro"
			(at 0 0 0)
			(layer "F.Fab")
			(hide yes)
			(effects
				(font
					(size 1 1)
					(thickness 0.15)
				)
			)
		)
		(property "License" "Apache-2.0"
			(at 0 0 0)
			(layer "F.Fab")
			(hide yes)
			(effects
				(font
					(size 1 1)
					(thickness 0.15)
				)
			)
		)
		(property "MPN" ""
			(at 0 0 0)
			(layer "F.Fab")
			(hide yes)
			(effects
				(font
					(size 1 1)
					(thickness 0.15)
				)
			)
		)
		(property "Manufacturer" ""
			(at 0 0 0)
			(layer "F.Fab")
			(hide yes)
			(effects
				(font
					(size 1 1)
					(thickness 0.15)
				)
			)
		)
		(property "Public" "False"
			(at 0 0 0)
			(layer "F.Fab")
			(hide yes)
			(effects
				(font
					(size 1 1)
					(thickness 0.15)
				)
			)
		)
		(sheetname "/WiFi_Bluetooth/")
		(sheetfile "wifi_bt.kicad_sch")
		(attr exclude_from_pos_files exclude_from_bom)
		(fp_circle
			(center 0 0)
			(end 0.475 0)
			(stroke
				(width 0.05)
				(type default)
			)
			(fill no)
			(layer "F.CrtYd")
		)
		(fp_text user "Author: Antmicro"
			(at -0.4 3.901 0)
			(layer "F.Fab")
			(effects
				(font
					(size 0.7 0.7)
					(thickness 0.15)
				)
				(justify left bottom)
			)
		)
		(fp_text user "${REFERENCE}"
			(at -0.4 2.7 0)
			(layer "F.Fab")
			(effects
				(font
					(size 0.7 0.7)
					(thickness 0.15)
				)
				(justify left bottom)
			)
		)
		(fp_text user "License: Apache-2.0"
			(at -0.4 5.101 0)
			(layer "F.Fab")
			(effects
				(font
					(size 0.7 0.7)
					(thickness 0.15)
				)
				(justify left bottom)
			)
		)
		(pad "1" smd circle
			(at 0 0)
			(size 0.75 0.75)
			(layers "F.Cu" "F.Mask")
			(net 526 "Net-(U26A-BT_HOST_WAKE)")
			(pinfunction "1")
			(pintype "passive")
		)
	)
	(footprint "antmicro-footprints:Oscillator_SMD_ECS_2520MV_2.5x2mm"
		(layer "F.Cu")
		(at 219.6 150.05 90)
		(descr "Miniature Crystal Clock Oscillator ECS 2520MV series")
		(tags "Crystal Clock Oscillator ECS 2520MV SMD")
		(property "Reference" "Y4"
			(at -0.05 2.4 90)
			(layer "F.SilkS")
			(effects
				(font
					(size 0.7 0.7)
					(thickness 0.15)
				)
				(justify left bottom)
			)
		)
		(property "Value" "Oscillator_32.768kHz_ECS_2520MV"
			(at 0 2.499 90)
			(layer "F.Fab")
			(hide yes)
			(effects
				(font
					(size 0.7 0.7)
					(thickness 0.15)
				)
				(justify left bottom)
			)
		)
		(property "Datasheet" "https://ecsxtal.com/store/pdf/ECS-327MVATX.pdf"
			(at 0 0 90)
			(layer "F.Fab")
			(hide yes)
			(effects
				(font
					(size 1.27 1.27)
					(thickness 0.15)
				)
			)
		)
		(property "Description" "32.768 kHz XO (Standard) CMOS Oscillator 1.6V ~ 3.6V Enable/Disable 4-SMD, No Lead"
			(at 0 0 90)
			(layer "F.Fab")
			(hide yes)
			(effects
				(font
					(size 1.27 1.27)
					(thickness 0.15)
				)
			)
		)
		(property "Author" "Antmicro"
			(at 369.65 -69.55 0)
			(layer "F.Fab")
			(hide yes)
			(effects
				(font
					(size 1 1)
					(thickness 0.15)
				)
			)
		)
		(property "License" "Apache-2.0"
			(at 369.65 -69.55 0)
			(layer "F.Fab")
			(hide yes)
			(effects
				(font
					(size 1 1)
					(thickness 0.15)
				)
			)
		)
		(property "MPN" "ECS-327MVATX-2-CN-TR3"
			(at 369.65 -69.55 0)
			(layer "F.Fab")
			(hide yes)
			(effects
				(font
					(size 1 1)
					(thickness 0.15)
				)
			)
		)
		(property "Manufacturer" "ECS Inc. International"
			(at 369.65 -69.55 0)
			(layer "F.Fab")
			(hide yes)
			(effects
				(font
					(size 1 1)
					(thickness 0.15)
				)
			)
		)
		(property "Public" ""
			(at 369.65 -69.55 0)
			(layer "F.Fab")
			(hide yes)
			(effects
				(font
					(size 1 1)
					(thickness 0.15)
				)
			)
		)
		(property "Val" "32.768 kHz"
			(at 369.65 -69.55 0)
			(layer "F.Fab")
			(hide yes)
			(effects
				(font
					(size 1 1)
					(thickness 0.15)
				)
			)
		)
		(sheetname "/WiFi_Bluetooth/")
		(sheetfile "wifi_bt.kicad_sch")
		(attr smd)
		(fp_line
			(start -0.16 -1.361)
			(end 0.17 -1.361)
			(stroke
				(width 0.15)
				(type solid)
			)
			(layer "F.SilkS")
		)
		(fp_line
			(start 1.11 0.32)
			(end 1.11 -0.32)
			(stroke
				(width 0.15)
				(type solid)
			)
			(layer "F.SilkS")
		)
		(fp_line
			(start -1.111 0.32)
			(end -1.111 -0.32)
			(stroke
				(width 0.15)
				(type solid)
			)
			(layer "F.SilkS")
		)
		(fp_line
			(start -0.172 1.36)
			(end 0.17 1.36)
			(stroke
				(width 0.15)
				(type solid)
			)
			(layer "F.SilkS")
		)
		(fp_circle
			(center -1.1 -1.5)
			(end -1.049 -1.5)
			(stroke
				(width 0.15)
				(type solid)
			)
			(fill yes)
			(layer "F.SilkS")
		)
		(fp_rect
			(start -1.25 -1.5)
			(end 1.25 1.5)
			(stroke
				(width 0.05)
				(type solid)
			)
			(fill no)
			(layer "F.CrtYd")
		)
		(fp_line
			(start -1 -0.75)
			(end -0.5 -1.25)
			(stroke
				(width 0.15)
				(type solid)
			)
			(layer "F.Fab")
		)
		(fp_rect
			(start 1 1.249)
			(end -1 -1.25)
			(stroke
				(width 0.15)
				(type solid)
			)
			(fill no)
			(layer "F.Fab")
		)
		(fp_text user "Author: Antmicro"
			(at -1.25 5.102 90)
			(layer "F.Fab")
			(effects
				(font
					(size 0.7 0.7)
					(thickness 0.15)
				)
				(justify left bottom)
			)
		)
		(fp_text user "${REFERENCE}"
			(at -1.25 3.9 90)
			(layer "F.Fab")
			(effects
				(font
					(size 0.7 0.7)
					(thickness 0.15)
				)
				(justify left bottom)
			)
		)
		(fp_text user "License: Apache-2.0"
			(at -1.25 6.302 90)
			(layer "F.Fab")
			(effects
				(font
					(size 0.7 0.7)
					(thickness 0.15)
				)
				(justify left bottom)
			)
		)
		(pad "1" smd roundrect
			(at -0.725 -0.927 90)
			(size 0.8 0.9)
			(layers "F.Cu" "F.Mask" "F.Paste")
			(roundrect_rratio 0.25)
			(net 50 "+3V3")
			(pinfunction "EN")
			(pintype "input")
		)
		(pad "2" smd roundrect
			(at -0.725 0.925 90)
			(size 0.8 0.9)
			(layers "F.Cu" "F.Mask" "F.Paste")
			(roundrect_rratio 0.25)
			(net 417 "GND")
			(pinfunction "GND")
			(pintype "power_in")
		)
		(pad "3" smd roundrect
			(at 0.723 0.925 90)
			(size 0.8 0.9)
			(layers "F.Cu" "F.Mask" "F.Paste")
			(roundrect_rratio 0.25)
			(net 430 "/WiFi_Bluetooth/LPO_IN")
			(pinfunction "OUT")
			(pintype "output")
		)
		(pad "4" smd roundrect
			(at 0.723 -0.927 90)
			(size 0.8 0.9)
			(layers "F.Cu" "F.Mask" "F.Paste")
			(roundrect_rratio 0.25)
			(net 50 "+3V3")
			(pinfunction "VDD")
			(pintype "power_in")
		)
	)
	(footprint "antmicro-footprints:TP_SMD_0.75mm"
		(layer "F.Cu")
		(at 180.72 145.3375 90)
		(property "Reference" "TP34"
			(at 0 -0.6 90)
			(layer "F.SilkS")
			(hide yes)
			(effects
				(font
					(size 0.7 0.7)
					(thickness 0.15)
				)
				(justify left bottom)
			)
		)
		(property "Value" "TP_0.75mm_SMD"
			(at 0 1.2 90)
			(layer "F.Fab")
			(hide yes)
			(effects
				(font
					(size 0.7 0.7)
					(thickness 0.15)
				)
				(justify left bottom)
			)
		)
		(property "Description" "SMT test point"
			(at 0 0 90)
			(layer "F.Fab")
			(hide yes)
			(effects
				(font
					(size 1.27 1.27)
					(thickness 0.15)
				)
			)
		)
		(property "Author" "Antmicro"
			(at 326.0575 -35.3825 0)
			(layer "F.Fab")
			(hide yes)
			(effects
				(font
					(size 1 1)
					(thickness 0.15)
				)
			)
		)
		(property "License" "Apache-2.0"
			(at 326.0575 -35.3825 0)
			(layer "F.Fab")
			(hide yes)
			(effects
				(font
					(size 1 1)
					(thickness 0.15)
				)
			)
		)
		(property "MPN" ""
			(at 326.0575 -35.3825 0)
			(layer "F.Fab")
			(hide yes)
			(effects
				(font
					(size 1 1)
					(thickness 0.15)
				)
			)
		)
		(property "Manufacturer" ""
			(at 326.0575 -35.3825 0)
			(layer "F.Fab")
			(hide yes)
			(effects
				(font
					(size 1 1)
					(thickness 0.15)
				)
			)
		)
		(property "Public" "False"
			(at 326.0575 -35.3825 0)
			(layer "F.Fab")
			(hide yes)
			(effects
				(font
					(size 1 1)
					(thickness 0.15)
				)
			)
		)
		(sheetname "/Supply/")
		(sheetfile "supply.kicad_sch")
		(attr exclude_from_pos_files exclude_from_bom)
		(fp_circle
			(center 0 0)
			(end 0.475 0)
			(stroke
				(width 0.05)
				(type default)
			)
			(fill no)
			(layer "F.CrtYd")
		)
		(fp_text user "License: Apache-2.0"
			(at -0.4 5.101 90)
			(layer "F.Fab")
			(effects
				(font
					(size 0.7 0.7)
					(thickness 0.15)
				)
				(justify left bottom)
			)
		)
		(fp_text user "Author: Antmicro"
			(at -0.4 3.901 90)
			(layer "F.Fab")
			(effects
				(font
					(size 0.7 0.7)
					(thickness 0.15)
				)
				(justify left bottom)
			)
		)
		(fp_text user "${REFERENCE}"
			(at -0.4 2.7 90)
			(layer "F.Fab")
			(effects
				(font
					(size 0.7 0.7)
					(thickness 0.15)
				)
				(justify left bottom)
			)
		)
		(pad "1" smd circle
			(at 0 0 90)
			(size 0.75 0.75)
			(layers "F.Cu" "F.Mask")
			(net 100 "/FPGA MSSIO/SUPPLY.SDA")
			(pinfunction "1")
			(pintype "passive")
		)
	)
	(footprint "antmicro-footprints:4x0R_0402_array_EXB28V"
		(layer "F.Cu")
		(at 193.085 144.45 180)
		(property "Reference" "R108"
			(at -1.265 1.95 0)
			(layer "F.SilkS")
			(effects
				(font
					(size 0.7 0.7)
					(thickness 0.15)
				)
				(justify right top)
			)
		)
		(property "Value" "4x0R_0402_array"
			(at 0.6604 2.8194 0)
			(layer "F.Fab")
			(hide yes)
			(effects
				(font
					(size 0.7 0.7)
					(thickness 0.15)
				)
				(justify right top)
			)
		)
		(property "Datasheet" "https://industrial.panasonic.com/cdbs/www-data/pdf/AOC0000/AOC0000C14.pdf"
			(at 0 0 0)
			(layer "F.Fab")
			(hide yes)
			(effects
				(font
					(size 1.27 1.27)
					(thickness 0.15)
				)
			)
		)
		(property "Description" "Zero Ohm Network Resistor, Jumper, 0402 [1005 Metric], Thick Film, Isolated, Convex, 4 Resistors"
			(at 0 0 0)
			(layer "F.Fab")
			(hide yes)
			(effects
				(font
					(size 1.27 1.27)
					(thickness 0.15)
				)
			)
		)
		(property "MPN" "EXB28VR000X"
			(at 0 0 180)
			(unlocked yes)
			(layer "F.Fab")
			(hide yes)
			(effects
				(font
					(size 1 1)
					(thickness 0.15)
				)
			)
		)
		(property "Manufacturer" "Panasonic"
			(at 0 0 180)
			(unlocked yes)
			(layer "F.Fab")
			(hide yes)
			(effects
				(font
					(size 1 1)
					(thickness 0.15)
				)
			)
		)
		(property "Author" "Antmicro"
			(at 0 0 180)
			(unlocked yes)
			(layer "F.Fab")
			(hide yes)
			(effects
				(font
					(size 1 1)
					(thickness 0.15)
				)
			)
		)
		(property "License" "Apache-2.0"
			(at 0 0 180)
			(unlocked yes)
			(layer "F.Fab")
			(hide yes)
			(effects
				(font
					(size 1 1)
					(thickness 0.15)
				)
			)
		)
		(property "Val" "4x0R_0402"
			(at 0 0 180)
			(unlocked yes)
			(layer "F.Fab")
			(hide yes)
			(effects
				(font
					(size 1 1)
					(thickness 0.15)
				)
			)
		)
		(sheetname "/HDMI/")
		(sheetfile "hdmi.kicad_sch")
		(attr smd)
		(fp_line
			(start 1.15 0.15)
			(end 1.15 -0.15)
			(stroke
				(width 0.15)
				(type solid)
			)
			(layer "F.SilkS")
		)
		(fp_line
			(start -1.15 -0.15)
			(end -1.15 0.15)
			(stroke
				(width 0.15)
				(type solid)
			)
			(layer "F.SilkS")
		)
		(fp_circle
			(center -0.9652 0.9144)
			(end -0.9144 0.9144)
			(stroke
				(width 0.15)
				(type solid)
			)
			(fill no)
			(layer "F.SilkS")
		)
		(fp_line
			(start 1.25 0.8)
			(end 1.25 -0.8)
			(stroke
				(width 0.05)
				(type solid)
			)
			(layer "F.CrtYd")
		)
		(fp_line
			(start 1.25 -0.8)
			(end -1.25 -0.8)
			(stroke
				(width 0.05)
				(type solid)
			)
			(layer "F.CrtYd")
		)
		(fp_line
			(start -1.25 0.8)
			(end 1.25 0.8)
			(stroke
				(width 0.05)
				(type solid)
			)
			(layer "F.CrtYd")
		)
		(fp_line
			(start -1.25 -0.8)
			(end -1.25 0.8)
			(stroke
				(width 0.05)
				(type solid)
			)
			(layer "F.CrtYd")
		)
		(fp_line
			(start 1 0.5)
			(end -1 0.5)
			(stroke
				(width 0.15)
				(type solid)
			)
			(layer "F.Fab")
		)
		(fp_line
			(start 1 -0.5)
			(end 1 0.5)
			(stroke
				(width 0.15)
				(type solid)
			)
			(layer "F.Fab")
		)
		(fp_line
			(start -1 0.5)
			(end -1 -0.5)
			(stroke
				(width 0.15)
				(type solid)
			)
			(layer "F.Fab")
		)
		(fp_line
			(start -1 0)
			(end -0.508 0.5)
			(stroke
				(width 0.15)
				(type solid)
			)
			(layer "F.Fab")
		)
		(fp_line
			(start -1 -0.5)
			(end 1 -0.5)
			(stroke
				(width 0.15)
				(type solid)
			)
			(layer "F.Fab")
		)
		(fp_circle
			(center -0.9652 0.9144)
			(end -0.9144 0.9144)
			(stroke
				(width 0.15)
				(type solid)
			)
			(fill no)
			(layer "F.Fab")
		)
		(fp_text user "License: Apache-2.0"
			(at -1.25 7.2194 0)
			(layer "F.Fab")
			(effects
				(font
					(size 0.7 0.7)
					(thickness 0.15)
				)
				(justify right top)
			)
		)
		(fp_text user "Author: Antmicro"
			(at -1.25 6.0194 0)
			(layer "F.Fab")
			(effects
				(font
					(size 0.7 0.7)
					(thickness 0.15)
				)
				(justify right top)
			)
		)
		(fp_text user "${REFERENCE}"
			(at -1.25 4.8194 0)
			(layer "F.Fab")
			(effects
				(font
					(size 0.7 0.7)
					(thickness 0.15)
				)
				(justify right top)
			)
		)
		(pad "1" smd roundrect
			(at -0.8875 0.45 180)
			(size 0.525 0.5)
			(layers "F.Cu" "F.Mask" "F.Paste")
			(roundrect_rratio 0.25)
			(net 86 "/FPGA GPIO/HDMI_FPGA.TX0_N")
			(pinfunction "R1.1")
			(pintype "passive")
		)
		(pad "2" smd roundrect
			(at -0.25 0.46 180)
			(size 0.25 0.48)
			(layers "F.Cu" "F.Mask" "F.Paste")
			(roundrect_rratio 0.25)
			(net 87 "/FPGA GPIO/HDMI_FPGA.TX0_P")
			(pinfunction "R2.1")
			(pintype "passive")
		)
		(pad "3" smd roundrect
			(at 0.25 0.46 180)
			(size 0.25 0.48)
			(layers "F.Cu" "F.Mask" "F.Paste")
			(roundrect_rratio 0.25)
			(net 88 "/FPGA GPIO/HDMI_FPGA.CLK_N")
			(pinfunction "R3.1")
			(pintype "passive")
		)
		(pad "4" smd roundrect
			(at 0.8875 0.45 180)
			(size 0.525 0.5)
			(layers "F.Cu" "F.Mask" "F.Paste")
			(roundrect_rratio 0.25)
			(net 89 "/FPGA GPIO/HDMI_FPGA.CLK_P")
			(pinfunction "R4.1")
			(pintype "passive")
		)
		(pad "5" smd roundrect
			(at 0.8875 -0.45 180)
			(size 0.525 0.5)
			(layers "F.Cu" "F.Mask" "F.Paste")
			(roundrect_rratio 0.25)
			(net 548 "/HDMI/PI3HDX_C_CLK_P")
			(pinfunction "R4.2")
			(pintype "passive")
		)
		(pad "6" smd roundrect
			(at 0.25 -0.46 180)
			(size 0.25 0.48)
			(layers "F.Cu" "F.Mask" "F.Paste")
			(roundrect_rratio 0.25)
			(net 552 "/HDMI/PI3HDX_C_CLK_N")
			(pinfunction "R3.2")
			(pintype "passive")
		)
		(pad "7" smd roundrect
			(at -0.25 -0.46 180)
			(size 0.25 0.48)
			(layers "F.Cu" "F.Mask" "F.Paste")
			(roundrect_rratio 0.25)
			(net 547 "/HDMI/PI3HDX_C_TX0_P")
			(pinfunction "R2.2")
			(pintype "passive")
		)
		(pad "8" smd roundrect
			(at -0.8875 -0.45 180)
			(size 0.525 0.5)
			(layers "F.Cu" "F.Mask" "F.Paste")
			(roundrect_rratio 0.25)
			(net 551 "/HDMI/PI3HDX_C_TX0_N")
			(pinfunction "R1.2")
			(pintype "passive")
		)
	)
)
